(kicad_pcb
	(version 20260206)
	(generator "pcbnew")
	(generator_version "10.0")
	(general
		(thickness 1.6)
		(legacy_teardrops no)
	)
	(paper "A4")
	(title_block
		(title "03242023_DA0F0TMBIJ0_F0T_Motherboard_J_brd_V01_OCP.brd")
		(comment 1 "Grand Teton / footprints 5310-5316 of 6105")
	)
	(layers
		(0 "F.Cu" signal "TOP")
		(4 "In1.Cu" signal "GND")
		(6 "In2.Cu" signal "IN1")
		(8 "In3.Cu" signal "GND1")
		(10 "In4.Cu" signal "IN2")
		(12 "In5.Cu" signal "GND2")
		(14 "In6.Cu" signal "IN3")
		(16 "In7.Cu" signal "GND3")
		(18 "In8.Cu" signal "VCC")
		(20 "In9.Cu" signal "VCC1")
		(22 "In10.Cu" signal "GND4")
		(24 "In11.Cu" signal "IN4")
		(26 "In12.Cu" signal "GND5")
		(28 "In13.Cu" signal "IN5")
		(30 "In14.Cu" signal "GND6")
		(32 "In15.Cu" signal "IN6")
		(34 "In16.Cu" signal "GND7")
		(2 "B.Cu" signal "BOTTOM")
		(9 "F.Adhes" user "F.Adhesive")
		(11 "B.Adhes" user "B.Adhesive")
		(13 "F.Paste" user "Package Geometry/Pastemask Top")
		(15 "B.Paste" user "Package Geometry/Pastemask Bottom")
		(5 "F.SilkS" user "Ref Des/Silkscreen Top")
		(7 "B.SilkS" user "Ref Des/Silkscreen Bottom")
		(1 "F.Mask" user "Board Geometry/Soldermask Top")
		(3 "B.Mask" user "Board Geometry/Soldermask Bottom")
		(17 "Dwgs.User" user "User.Drawings")
		(19 "Cmts.User" user "User.Comments")
		(21 "Eco1.User" user "User.Eco1")
		(23 "Eco2.User" user "User.Eco2")
		(25 "Edge.Cuts" user "Board Geometry/Outline")
		(27 "Margin" user)
		(31 "F.CrtYd" user "Package Geometry/Place Bound Top")
		(29 "B.CrtYd" user "Package Geometry/Place Bound Bottom")
		(35 "F.Fab" user "Ref Des/Assembly Top")
		(33 "B.Fab" user "Ref Des/Assembly Bottom")
	)
	(footprint ""
		(layer "B.Cu")
		(at 114.13744 -413.093408)
		(property "Reference" "C2335"
			(at 0 0 0)
			(layer "B.SilkS")
			(hide yes)
			(effects
				(font
					(size 1.27 1.27)
				)
				(justify mirror)
			)
		)
		(property "Value" ""
			(at 0 0 0)
			(layer "B.Fab")
			(effects
				(font
					(size 1.27 1.27)
				)
				(justify mirror)
			)
		)
		(duplicate_pad_numbers_are_jumpers no)
		(fp_line
			(start -0.7874 -0.4064)
			(end -0.7874 0.4064)
			(stroke
				(width 0.1524)
				(type default)
			)
			(layer "B.SilkS")
		)
		(fp_line
			(start -0.7874 0.4064)
			(end 0.7874 0.4064)
			(stroke
				(width 0.1524)
				(type default)
			)
			(layer "B.SilkS")
		)
		(fp_line
			(start 0.7874 -0.4064)
			(end -0.7874 -0.4064)
			(stroke
				(width 0.1524)
				(type default)
			)
			(layer "B.SilkS")
		)
		(fp_line
			(start 0.7874 0.4064)
			(end 0.7874 -0.4064)
			(stroke
				(width 0.1524)
				(type default)
			)
			(layer "B.SilkS")
		)
		(fp_line
			(start -0.67945 -0.3048)
			(end -0.67945 0.3048)
			(stroke
				(width 0.1)
				(type default)
			)
			(layer "B.Fab")
		)
		(fp_line
			(start -0.67945 0.3048)
			(end -0.120396 0.3048)
			(stroke
				(width 0.1)
				(type default)
			)
			(layer "B.Fab")
		)
		(fp_line
			(start -0.12065 -0.3048)
			(end -0.67945 -0.3048)
			(stroke
				(width 0.1)
				(type default)
			)
			(layer "B.Fab")
		)
		(fp_line
			(start -0.12065 -0.2794)
			(end -0.12065 -0.3048)
			(stroke
				(width 0.1)
				(type default)
			)
			(layer "B.Fab")
		)
		(fp_line
			(start -0.120396 0.2794)
			(end 0.12065 0.2794)
			(stroke
				(width 0.1)
				(type default)
			)
			(layer "B.Fab")
		)
		(fp_line
			(start -0.120396 0.3048)
			(end -0.120396 0.2794)
			(stroke
				(width 0.1)
				(type default)
			)
			(layer "B.Fab")
		)
		(fp_line
			(start 0.12065 -0.305054)
			(end 0.12065 -0.2794)
			(stroke
				(width 0.1)
				(type default)
			)
			(layer "B.Fab")
		)
		(fp_line
			(start 0.12065 -0.2794)
			(end -0.12065 -0.2794)
			(stroke
				(width 0.1)
				(type default)
			)
			(layer "B.Fab")
		)
		(fp_line
			(start 0.12065 0.2794)
			(end 0.12065 0.3048)
			(stroke
				(width 0.1)
				(type default)
			)
			(layer "B.Fab")
		)
		(fp_line
			(start 0.12065 0.3048)
			(end 0.67945 0.3048)
			(stroke
				(width 0.1)
				(type default)
			)
			(layer "B.Fab")
		)
		(fp_line
			(start 0.67945 -0.305054)
			(end 0.12065 -0.305054)
			(stroke
				(width 0.1)
				(type default)
			)
			(layer "B.Fab")
		)
		(fp_line
			(start 0.67945 0.3048)
			(end 0.67945 -0.305054)
			(stroke
				(width 0.1)
				(type default)
			)
			(layer "B.Fab")
		)
		(pad "1" smd circle
			(at 0.40005 0 180)
			(size 0 0)
			(layers "B.Cu" "B.Mask" "B.Paste")
			(net "P3V3_9ZXL045_VDDR")
		)
		(pad "2" smd circle
			(at -0.40005 0 180)
			(size 0 0)
			(layers "B.Cu" "B.Mask" "B.Paste")
			(net "GND")
		)
	)
	(footprint ""
		(layer "B.Cu")
		(at 119.95912 -248.49836 -90)
		(property "Reference" "C447"
			(at 0 0 90)
			(layer "B.SilkS")
			(hide yes)
			(effects
				(font
					(size 1.27 1.27)
				)
				(justify mirror)
			)
		)
		(property "Value" ""
			(at 0 0 90)
			(layer "B.Fab")
			(effects
				(font
					(size 1.27 1.27)
				)
				(justify mirror)
			)
		)
		(duplicate_pad_numbers_are_jumpers no)
		(fp_line
			(start -1.524 0.762)
			(end 1.524 0.762)
			(stroke
				(width 0.1524)
				(type default)
			)
			(layer "B.SilkS")
		)
		(fp_line
			(start 1.524 0.762)
			(end 1.524 -0.762)
			(stroke
				(width 0.1524)
				(type default)
			)
			(layer "B.SilkS")
		)
		(fp_line
			(start -1.524 -0.762)
			(end -1.524 0.762)
			(stroke
				(width 0.1524)
				(type default)
			)
			(layer "B.SilkS")
		)
		(fp_line
			(start 1.524 -0.762)
			(end -1.524 -0.762)
			(stroke
				(width 0.1524)
				(type default)
			)
			(layer "B.SilkS")
		)
		(fp_line
			(start -1.1049 0.724916)
			(end -1.1049 -0.724916)
			(stroke
				(width 0.1)
				(type default)
			)
			(layer "B.Fab")
		)
		(fp_line
			(start 1.1049 0.724916)
			(end -1.1049 0.724916)
			(stroke
				(width 0.1)
				(type default)
			)
			(layer "B.Fab")
		)
		(fp_line
			(start -1.1049 -0.724916)
			(end 1.1049 -0.724916)
			(stroke
				(width 0.1)
				(type default)
			)
			(layer "B.Fab")
		)
		(fp_line
			(start 1.1049 -0.724916)
			(end 1.1049 0.724916)
			(stroke
				(width 0.1)
				(type default)
			)
			(layer "B.Fab")
		)
		(pad "1" smd rect
			(at 0.889 0 270)
			(size 1.016 1.27)
			(layers "B.Cu" "B.Mask" "B.Paste")
			(net "PVCCD_HV_CPU1")
		)
		(pad "2" smd rect
			(at -0.889 0 270)
			(size 1.016 1.27)
			(layers "B.Cu" "B.Mask" "B.Paste")
			(net "GND")
		)
	)
	(footprint ""
		(layer "B.Cu")
		(at 180.848 -18.710148 90)
		(property "Reference" "R2420"
			(at 0 0 90)
			(layer "B.SilkS")
			(hide yes)
			(effects
				(font
					(size 1.27 1.27)
				)
				(justify mirror)
			)
		)
		(property "Value" ""
			(at 0 0 90)
			(layer "B.Fab")
			(effects
				(font
					(size 1.27 1.27)
				)
				(justify mirror)
			)
		)
		(duplicate_pad_numbers_are_jumpers no)
		(fp_line
			(start 0.7874 -0.4064)
			(end -0.7874 -0.4064)
			(stroke
				(width 0.1524)
				(type default)
			)
			(layer "B.SilkS")
		)
		(fp_line
			(start -0.7874 -0.4064)
			(end -0.7874 0.4064)
			(stroke
				(width 0.1524)
				(type default)
			)
			(layer "B.SilkS")
		)
		(fp_line
			(start 0.7874 0.4064)
			(end 0.7874 -0.4064)
			(stroke
				(width 0.1524)
				(type default)
			)
			(layer "B.SilkS")
		)
		(fp_line
			(start -0.7874 0.4064)
			(end 0.7874 0.4064)
			(stroke
				(width 0.1524)
				(type default)
			)
			(layer "B.SilkS")
		)
		(fp_line
			(start 0.67945 -0.305054)
			(end 0.12065 -0.305054)
			(stroke
				(width 0.1)
				(type default)
			)
			(layer "B.Fab")
		)
		(fp_line
			(start 0.12065 -0.305054)
			(end 0.12065 -0.2794)
			(stroke
				(width 0.1)
				(type default)
			)
			(layer "B.Fab")
		)
		(fp_line
			(start -0.12065 -0.3048)
			(end -0.67945 -0.3048)
			(stroke
				(width 0.1)
				(type default)
			)
			(layer "B.Fab")
		)
		(fp_line
			(start -0.67945 -0.3048)
			(end -0.67945 0.3048)
			(stroke
				(width 0.1)
				(type default)
			)
			(layer "B.Fab")
		)
		(fp_line
			(start 0.12065 -0.2794)
			(end -0.12065 -0.2794)
			(stroke
				(width 0.1)
				(type default)
			)
			(layer "B.Fab")
		)
		(fp_line
			(start -0.12065 -0.2794)
			(end -0.12065 -0.3048)
			(stroke
				(width 0.1)
				(type default)
			)
			(layer "B.Fab")
		)
		(fp_line
			(start 0.12065 0.2794)
			(end 0.12065 0.3048)
			(stroke
				(width 0.1)
				(type default)
			)
			(layer "B.Fab")
		)
		(fp_line
			(start -0.120396 0.2794)
			(end 0.12065 0.2794)
			(stroke
				(width 0.1)
				(type default)
			)
			(layer "B.Fab")
		)
		(fp_line
			(start 0.67945 0.3048)
			(end 0.67945 -0.305054)
			(stroke
				(width 0.1)
				(type default)
			)
			(layer "B.Fab")
		)
		(fp_line
			(start 0.12065 0.3048)
			(end 0.67945 0.3048)
			(stroke
				(width 0.1)
				(type default)
			)
			(layer "B.Fab")
		)
		(fp_line
			(start -0.120396 0.3048)
			(end -0.120396 0.2794)
			(stroke
				(width 0.1)
				(type default)
			)
			(layer "B.Fab")
		)
		(fp_line
			(start -0.67945 0.3048)
			(end -0.120396 0.3048)
			(stroke
				(width 0.1)
				(type default)
			)
			(layer "B.Fab")
		)
		(pad "1" smd circle
			(at 0.40005 0 270)
			(size 0 0)
			(layers "B.Cu" "B.Mask" "B.Paste")
			(net "SMB_HOST_3V3AUX_SDA")
		)
		(pad "2" smd circle
			(at -0.40005 0 270)
			(size 0 0)
			(layers "B.Cu" "B.Mask" "B.Paste")
			(net "SMB_HOST_3V3AUX_SDA_R0")
		)
	)
	(footprint ""
		(layer "B.Cu")
		(at 364.342934 -255.853946 -90)
		(property "Reference" "C355"
			(at 0 0 90)
			(layer "B.SilkS")
			(hide yes)
			(effects
				(font
					(size 1.27 1.27)
				)
				(justify mirror)
			)
		)
		(property "Value" ""
			(at 0 0 90)
			(layer "B.Fab")
			(effects
				(font
					(size 1.27 1.27)
				)
				(justify mirror)
			)
		)
		(duplicate_pad_numbers_are_jumpers no)
		(fp_line
			(start -1.524 0.762)
			(end 1.524 0.762)
			(stroke
				(width 0.1524)
				(type default)
			)
			(layer "B.SilkS")
		)
		(fp_line
			(start 1.524 0.762)
			(end 1.524 -0.762)
			(stroke
				(width 0.1524)
				(type default)
			)
			(layer "B.SilkS")
		)
		(fp_line
			(start -1.524 -0.762)
			(end -1.524 0.762)
			(stroke
				(width 0.1524)
				(type default)
			)
			(layer "B.SilkS")
		)
		(fp_line
			(start 1.524 -0.762)
			(end -1.524 -0.762)
			(stroke
				(width 0.1524)
				(type default)
			)
			(layer "B.SilkS")
		)
		(fp_line
			(start -1.1049 0.724916)
			(end -1.1049 -0.724916)
			(stroke
				(width 0.1)
				(type default)
			)
			(layer "B.Fab")
		)
		(fp_line
			(start 1.1049 0.724916)
			(end -1.1049 0.724916)
			(stroke
				(width 0.1)
				(type default)
			)
			(layer "B.Fab")
		)
		(fp_line
			(start -1.1049 -0.724916)
			(end 1.1049 -0.724916)
			(stroke
				(width 0.1)
				(type default)
			)
			(layer "B.Fab")
		)
		(fp_line
			(start 1.1049 -0.724916)
			(end 1.1049 0.724916)
			(stroke
				(width 0.1)
				(type default)
			)
			(layer "B.Fab")
		)
		(pad "1" smd rect
			(at 0.889 0 270)
			(size 1.016 1.27)
			(layers "B.Cu" "B.Mask" "B.Paste")
			(net "PVCCIN_CPU0")
		)
		(pad "2" smd rect
			(at -0.889 0 270)
			(size 1.016 1.27)
			(layers "B.Cu" "B.Mask" "B.Paste")
			(net "GND")
		)
	)
	(footprint ""
		(layer "B.Cu")
		(at 113.78438 -361.764326)
		(property "Reference" "PR303"
			(at 0 0 0)
			(layer "B.SilkS")
			(hide yes)
			(effects
				(font
					(size 1.27 1.27)
				)
				(justify mirror)
			)
		)
		(property "Value" ""
			(at 0 0 0)
			(layer "B.Fab")
			(effects
				(font
					(size 1.27 1.27)
				)
				(justify mirror)
			)
		)
		(duplicate_pad_numbers_are_jumpers no)
		(fp_line
			(start -0.7874 -0.4064)
			(end -0.7874 0.4064)
			(stroke
				(width 0.1524)
				(type default)
			)
			(layer "B.SilkS")
		)
		(fp_line
			(start -0.7874 0.4064)
			(end 0.7874 0.4064)
			(stroke
				(width 0.1524)
				(type default)
			)
			(layer "B.SilkS")
		)
		(fp_line
			(start 0.7874 -0.4064)
			(end -0.7874 -0.4064)
			(stroke
				(width 0.1524)
				(type default)
			)
			(layer "B.SilkS")
		)
		(fp_line
			(start 0.7874 0.4064)
			(end 0.7874 -0.4064)
			(stroke
				(width 0.1524)
				(type default)
			)
			(layer "B.SilkS")
		)
		(fp_line
			(start -0.67945 -0.3048)
			(end -0.67945 0.3048)
			(stroke
				(width 0.1)
				(type default)
			)
			(layer "B.Fab")
		)
		(fp_line
			(start -0.67945 0.3048)
			(end -0.120396 0.3048)
			(stroke
				(width 0.1)
				(type default)
			)
			(layer "B.Fab")
		)
		(fp_line
			(start -0.12065 -0.3048)
			(end -0.67945 -0.3048)
			(stroke
				(width 0.1)
				(type default)
			)
			(layer "B.Fab")
		)
		(fp_line
			(start -0.12065 -0.2794)
			(end -0.12065 -0.3048)
			(stroke
				(width 0.1)
				(type default)
			)
			(layer "B.Fab")
		)
		(fp_line
			(start -0.120396 0.2794)
			(end 0.12065 0.2794)
			(stroke
				(width 0.1)
				(type default)
			)
			(layer "B.Fab")
		)
		(fp_line
			(start -0.120396 0.3048)
			(end -0.120396 0.2794)
			(stroke
				(width 0.1)
				(type default)
			)
			(layer "B.Fab")
		)
		(fp_line
			(start 0.12065 -0.305054)
			(end 0.12065 -0.2794)
			(stroke
				(width 0.1)
				(type default)
			)
			(layer "B.Fab")
		)
		(fp_line
			(start 0.12065 -0.2794)
			(end -0.12065 -0.2794)
			(stroke
				(width 0.1)
				(type default)
			)
			(layer "B.Fab")
		)
		(fp_line
			(start 0.12065 0.2794)
			(end 0.12065 0.3048)
			(stroke
				(width 0.1)
				(type default)
			)
			(layer "B.Fab")
		)
		(fp_line
			(start 0.12065 0.3048)
			(end 0.67945 0.3048)
			(stroke
				(width 0.1)
				(type default)
			)
			(layer "B.Fab")
		)
		(fp_line
			(start 0.67945 -0.305054)
			(end 0.12065 -0.305054)
			(stroke
				(width 0.1)
				(type default)
			)
			(layer "B.Fab")
		)
		(fp_line
			(start 0.67945 0.3048)
			(end 0.67945 -0.305054)
			(stroke
				(width 0.1)
				(type default)
			)
			(layer "B.Fab")
		)
		(pad "1" smd circle
			(at 0.40005 0 180)
			(size 0 0)
			(layers "B.Cu" "B.Mask" "B.Paste")
			(net "P12V_AUX")
		)
		(pad "2" smd circle
			(at -0.40005 0 180)
			(size 0 0)
			(layers "B.Cu" "B.Mask" "B.Paste")
			(net "PVCCIN_CPU1_VIN_CSNIN")
		)
	)
	(footprint ""
		(layer "B.Cu")
		(at 8.19277 -113.161826)
		(property "Reference" "R5238"
			(at 0 0 0)
			(layer "B.SilkS")
			(hide yes)
			(effects
				(font
					(size 1.27 1.27)
				)
				(justify mirror)
			)
		)
		(property "Value" ""
			(at 0 0 0)
			(layer "B.Fab")
			(effects
				(font
					(size 1.27 1.27)
				)
				(justify mirror)
			)
		)
		(duplicate_pad_numbers_are_jumpers no)
		(fp_line
			(start -0.7874 -0.4064)
			(end -0.7874 0.4064)
			(stroke
				(width 0.1524)
				(type default)
			)
			(layer "B.SilkS")
		)
		(fp_line
			(start -0.7874 0.4064)
			(end 0.7874 0.4064)
			(stroke
				(width 0.1524)
				(type default)
			)
			(layer "B.SilkS")
		)
		(fp_line
			(start 0.7874 -0.4064)
			(end -0.7874 -0.4064)
			(stroke
				(width 0.1524)
				(type default)
			)
			(layer "B.SilkS")
		)
		(fp_line
			(start 0.7874 0.4064)
			(end 0.7874 -0.4064)
			(stroke
				(width 0.1524)
				(type default)
			)
			(layer "B.SilkS")
		)
		(fp_line
			(start -0.67945 -0.3048)
			(end -0.67945 0.3048)
			(stroke
				(width 0.1)
				(type default)
			)
			(layer "B.Fab")
		)
		(fp_line
			(start -0.67945 0.3048)
			(end -0.120396 0.3048)
			(stroke
				(width 0.1)
				(type default)
			)
			(layer "B.Fab")
		)
		(fp_line
			(start -0.12065 -0.3048)
			(end -0.67945 -0.3048)
			(stroke
				(width 0.1)
				(type default)
			)
			(layer "B.Fab")
		)
		(fp_line
			(start -0.12065 -0.2794)
			(end -0.12065 -0.3048)
			(stroke
				(width 0.1)
				(type default)
			)
			(layer "B.Fab")
		)
		(fp_line
			(start -0.120396 0.2794)
			(end 0.12065 0.2794)
			(stroke
				(width 0.1)
				(type default)
			)
			(layer "B.Fab")
		)
		(fp_line
			(start -0.120396 0.3048)
			(end -0.120396 0.2794)
			(stroke
				(width 0.1)
				(type default)
			)
			(layer "B.Fab")
		)
		(fp_line
			(start 0.12065 -0.305054)
			(end 0.12065 -0.2794)
			(stroke
				(width 0.1)
				(type default)
			)
			(layer "B.Fab")
		)
		(fp_line
			(start 0.12065 -0.2794)
			(end -0.12065 -0.2794)
			(stroke
				(width 0.1)
				(type default)
			)
			(layer "B.Fab")
		)
		(fp_line
			(start 0.12065 0.2794)
			(end 0.12065 0.3048)
			(stroke
				(width 0.1)
				(type default)
			)
			(layer "B.Fab")
		)
		(fp_line
			(start 0.12065 0.3048)
			(end 0.67945 0.3048)
			(stroke
				(width 0.1)
				(type default)
			)
			(layer "B.Fab")
		)
		(fp_line
			(start 0.67945 -0.305054)
			(end 0.12065 -0.305054)
			(stroke
				(width 0.1)
				(type default)
			)
			(layer "B.Fab")
		)
		(fp_line
			(start 0.67945 0.3048)
			(end 0.67945 -0.305054)
			(stroke
				(width 0.1)
				(type default)
			)
			(layer "B.Fab")
		)
		(pad "1" smd circle
			(at 0.40005 0 180)
			(size 0 0)
			(layers "B.Cu" "B.Mask" "B.Paste")
			(net "PD_U5201_EQ")
		)
		(pad "2" smd circle
			(at -0.40005 0 180)
			(size 0 0)
			(layers "B.Cu" "B.Mask" "B.Paste")
			(net "GND")
		)
	)
	(footprint ""
		(layer "B.Cu")
		(at 107.457494 -259.53212 90)
		(property "Reference" "C457"
			(at 0 0 90)
			(layer "B.SilkS")
			(hide yes)
			(effects
				(font
					(size 1.27 1.27)
				)
				(justify mirror)
			)
		)
		(property "Value" ""
			(at 0 0 90)
			(layer "B.Fab")
			(effects
				(font
					(size 1.27 1.27)
				)
				(justify mirror)
			)
		)
		(duplicate_pad_numbers_are_jumpers no)
		(fp_line
			(start 1.524 -0.762)
			(end -1.524 -0.762)
			(stroke
				(width 0.1524)
				(type default)
			)
			(layer "B.SilkS")
		)
		(fp_line
			(start -1.524 -0.762)
			(end -1.524 0.762)
			(stroke
				(width 0.1524)
				(type default)
			)
			(layer "B.SilkS")
		)
		(fp_line
			(start 1.524 0.762)
			(end 1.524 -0.762)
			(stroke
				(width 0.1524)
				(type default)
			)
			(layer "B.SilkS")
		)
		(fp_line
			(start -1.524 0.762)
			(end 1.524 0.762)
			(stroke
				(width 0.1524)
				(type default)
			)
			(layer "B.SilkS")
		)
		(fp_line
			(start 1.1049 -0.724916)
			(end 1.1049 0.724916)
			(stroke
				(width 0.1)
				(type default)
			)
			(layer "B.Fab")
		)
		(fp_line
			(start -1.1049 -0.724916)
			(end 1.1049 -0.724916)
			(stroke
				(width 0.1)
				(type default)
			)
			(layer "B.Fab")
		)
		(fp_line
			(start 1.1049 0.724916)
			(end -1.1049 0.724916)
			(stroke
				(width 0.1)
				(type default)
			)
			(layer "B.Fab")
		)
		(fp_line
			(start -1.1049 0.724916)
			(end -1.1049 -0.724916)
			(stroke
				(width 0.1)
				(type default)
			)
			(layer "B.Fab")
		)
		(pad "1" smd rect
			(at 0.889 0 90)
			(size 1.016 1.27)
			(layers "B.Cu" "B.Mask" "B.Paste")
			(net "PVCCFA_EHV_FIVRA_CPU1")
		)
		(pad "2" smd rect
			(at -0.889 0 90)
			(size 1.016 1.27)
			(layers "B.Cu" "B.Mask" "B.Paste")
			(net "GND")
		)
	)
)
